(kicad_pcb
	(version 20260206)
	(generator "pcbnew")
	(generator_version "10.0")
	(general
		(thickness 1.6)
		(legacy_teardrops no)
	)
	(paper "A4")
	(title_block
		(title "01162023_DA0F0TEBIF0_F0T_Expander_BD_F_brd_V02_OCP.brd")
		(comment 1 "Grand Teton / footprint 3855 of 9728 (J9), pads 1-77 of 142")
	)
	(layers
		(0 "F.Cu" signal "TOP")
		(4 "In1.Cu" signal "GND")
		(6 "In2.Cu" signal "VCC")
		(8 "In3.Cu" signal "VCC1")
		(10 "In4.Cu" signal "GND1")
		(12 "In5.Cu" signal "IN1")
		(14 "In6.Cu" signal "GND2")
		(16 "In7.Cu" signal "IN2")
		(18 "In8.Cu" signal "GND3")
		(20 "In9.Cu" signal "IN3")
		(22 "In10.Cu" signal "GND4")
		(24 "In11.Cu" signal "IN4")
		(26 "In12.Cu" signal "GND5")
		(28 "In13.Cu" signal "IN5")
		(30 "In14.Cu" signal "GND6")
		(32 "In15.Cu" signal "IN6")
		(34 "In16.Cu" signal "GND7")
		(2 "B.Cu" signal "BOTTOM")
		(9 "F.Adhes" user "F.Adhesive")
		(11 "B.Adhes" user "B.Adhesive")
		(13 "F.Paste" user "Package Geometry/Pastemask Top")
		(15 "B.Paste" user "Package Geometry/Pastemask Bottom")
		(5 "F.SilkS" user "Ref Des/Silkscreen Top")
		(7 "B.SilkS" user "Ref Des/Silkscreen Bottom")
		(1 "F.Mask" user "Board Geometry/Soldermask Top")
		(3 "B.Mask" user "Board Geometry/Soldermask Bottom")
		(17 "Dwgs.User" user "User.Drawings")
		(19 "Cmts.User" user "User.Comments")
		(21 "Eco1.User" user "User.Eco1")
		(23 "Eco2.User" user "User.Eco2")
		(25 "Edge.Cuts" user "Board Geometry/Outline")
		(27 "Margin" user)
		(31 "F.CrtYd" user "Package Geometry/Place Bound Top")
		(29 "B.CrtYd" user "Package Geometry/Place Bound Bottom")
		(35 "F.Fab" user "Ref Des/Assembly Top")
		(33 "B.Fab" user "Ref Des/Assembly Bottom")
	)
	(footprint ""
		(layer "F.Cu")
		(at 419.48989 -412.090108)
		(property "Reference" "J9"
			(at -5.783834 6.071108 90)
			(unlocked yes)
			(layer "F.SilkS")
			(effects
				(font
					(size 2.032 1.524)
					(thickness 0.1524)
				)
				(justify left)
			)
		)
		(property "Value" ""
			(at 0 0 0)
			(layer "F.Fab")
			(effects
				(font
					(size 1.27 1.27)
				)
			)
		)
		(duplicate_pad_numbers_are_jumpers no)
		(pad "A1" thru_hole rect
			(at 0 0 180)
			(size 0.71628 0.71628)
			(drill 0.30988)
			(layers "*.Cu" "*.Mask")
			(remove_unused_layers no)
			(net "Net_8781")
			(clearance 0.0508)
			(thermal_gap 0.0508)
			(padstack
				(mode front_inner_back)
				(layer "Inner"
					(shape circle)
					(size 0.71628 0.71628)
					(clearance 0.0508)
				)
				(layer "B.Cu"
					(shape rect)
					(size 0.71628 0.71628)
					(clearance 0.0508)
				)
			)
		)
		(pad "A2" thru_hole circle
			(at 2.199894 0.199898 180)
			(size 0.906272 0.906272)
			(drill 0.499872)
			(layers "*.Cu" "*.Mask")
			(remove_unused_layers no)
			(net "GND")
			(clearance 0.0508)
			(thermal_gap 0.0508)
		)
		(pad "A3" thru_hole circle
			(at 4.400042 0 180)
			(size 0.71628 0.71628)
			(drill 0.30988)
			(layers "*.Cu" "*.Mask")
			(remove_unused_layers no)
			(net "Net_8779")
			(clearance 0.0508)
			(thermal_gap 0.0508)
		)
		(pad "A4" thru_hole circle
			(at 6.599936 0.199898 180)
			(size 0.906272 0.906272)
			(drill 0.499872)
			(layers "*.Cu" "*.Mask")
			(remove_unused_layers no)
			(net "GND")
			(clearance 0.0508)
			(thermal_gap 0.0508)
		)
		(pad "A5" thru_hole circle
			(at 8.800084 0 180)
			(size 0.71628 0.71628)
			(drill 0.30988)
			(layers "*.Cu" "*.Mask")
			(remove_unused_layers no)
			(net "Net_8777")
			(clearance 0.0508)
			(thermal_gap 0.0508)
		)
		(pad "A6" thru_hole circle
			(at 10.999978 0.199898 180)
			(size 0.906272 0.906272)
			(drill 0.499872)
			(layers "*.Cu" "*.Mask")
			(remove_unused_layers no)
			(net "GND")
			(clearance 0.0508)
			(thermal_gap 0.0508)
		)
		(pad "A7" thru_hole circle
			(at 13.199872 0 180)
			(size 0.71628 0.71628)
			(drill 0.30988)
			(layers "*.Cu" "*.Mask")
			(remove_unused_layers no)
			(net "PRSNT_GPU_A1_N")
			(clearance 0.0508)
			(thermal_gap 0.0508)
		)
		(pad "A8" thru_hole circle
			(at 15.40002 0.199898 180)
			(size 0.906272 0.906272)
			(drill 0.499872)
			(layers "*.Cu" "*.Mask")
			(remove_unused_layers no)
			(net "GND")
			(clearance 0.0508)
			(thermal_gap 0.0508)
		)
		(pad "A9" thru_hole circle
			(at 17.599914 0 180)
			(size 0.71628 0.71628)
			(drill 0.30988)
			(layers "*.Cu" "*.Mask")
			(remove_unused_layers no)
			(net "GPU_3V3IO_RSVD1")
			(clearance 0.0508)
			(thermal_gap 0.0508)
		)
		(pad "A10" thru_hole circle
			(at 19.800062 0.199898 180)
			(size 0.906272 0.906272)
			(drill 0.499872)
			(layers "*.Cu" "*.Mask")
			(remove_unused_layers no)
			(net "GND")
			(clearance 0.0508)
			(thermal_gap 0.0508)
		)
		(pad "B1" thru_hole circle
			(at 0 1.299972 180)
			(size 0.906272 0.906272)
			(drill 0.499872)
			(layers "*.Cu" "*.Mask")
			(remove_unused_layers no)
			(net "GND")
			(clearance 0.0508)
			(thermal_gap 0.0508)
		)
		(pad "B3" thru_hole circle
			(at 4.400042 1.299972 180)
			(size 0.906272 0.906272)
			(drill 0.499872)
			(layers "*.Cu" "*.Mask")
			(remove_unused_layers no)
			(net "GND")
			(clearance 0.0508)
			(thermal_gap 0.0508)
		)
		(pad "B5" thru_hole circle
			(at 8.800084 1.299972 180)
			(size 0.906272 0.906272)
			(drill 0.499872)
			(layers "*.Cu" "*.Mask")
			(remove_unused_layers no)
			(net "GND")
			(clearance 0.0508)
			(thermal_gap 0.0508)
		)
		(pad "B7" thru_hole circle
			(at 13.199872 1.299972 180)
			(size 0.906272 0.906272)
			(drill 0.499872)
			(layers "*.Cu" "*.Mask")
			(remove_unused_layers no)
			(net "GND")
			(clearance 0.0508)
			(thermal_gap 0.0508)
		)
		(pad "B9" thru_hole circle
			(at 17.599914 1.299972 180)
			(size 0.906272 0.906272)
			(drill 0.499872)
			(layers "*.Cu" "*.Mask")
			(remove_unused_layers no)
			(net "GND")
			(clearance 0.0508)
			(thermal_gap 0.0508)
		)
		(pad "B10" thru_hole circle
			(at 19.800062 1.500124 180)
			(size 0.71628 0.71628)
			(drill 0.30988)
			(layers "*.Cu" "*.Mask")
			(remove_unused_layers no)
			(net "Net_8774")
			(clearance 0.0508)
			(thermal_gap 0.0508)
		)
		(pad "C9" thru_hole circle
			(at 17.599914 2.599944 180)
			(size 0.71628 0.71628)
			(drill 0.30988)
			(layers "*.Cu" "*.Mask")
			(remove_unused_layers no)
			(net "Net_8772")
			(clearance 0.0508)
			(thermal_gap 0.0508)
		)
		(pad "C10" thru_hole circle
			(at 19.800062 2.800096 180)
			(size 0.71628 0.71628)
			(drill 0.30988)
			(layers "*.Cu" "*.Mask")
			(remove_unused_layers no)
			(net "Net_8773")
			(clearance 0.0508)
			(thermal_gap 0.0508)
		)
		(pad "D2" thru_hole circle
			(at 2.199894 4.100068 180)
			(size 0.906272 0.906272)
			(drill 0.499872)
			(layers "*.Cu" "*.Mask")
			(remove_unused_layers no)
			(net "GND")
			(clearance 0.0508)
			(thermal_gap 0.0508)
		)
		(pad "D4" thru_hole circle
			(at 6.599936 4.100068 180)
			(size 0.906272 0.906272)
			(drill 0.499872)
			(layers "*.Cu" "*.Mask")
			(remove_unused_layers no)
			(net "GND")
			(clearance 0.0508)
			(thermal_gap 0.0508)
		)
		(pad "D6" thru_hole circle
			(at 10.999978 4.100068 180)
			(size 0.906272 0.906272)
			(drill 0.499872)
			(layers "*.Cu" "*.Mask")
			(remove_unused_layers no)
			(net "GND")
			(clearance 0.0508)
			(thermal_gap 0.0508)
		)
		(pad "D8" thru_hole circle
			(at 15.40002 4.100068 180)
			(size 0.906272 0.906272)
			(drill 0.499872)
			(layers "*.Cu" "*.Mask")
			(remove_unused_layers no)
			(net "GND")
			(clearance 0.0508)
			(thermal_gap 0.0508)
		)
		(pad "D9" thru_hole circle
			(at 17.599914 3.899916 180)
			(size 0.71628 0.71628)
			(drill 0.30988)
			(layers "*.Cu" "*.Mask")
			(remove_unused_layers no)
			(net "GPU_3V3IO_RSVD3")
			(clearance 0.0508)
			(thermal_gap 0.0508)
		)
		(pad "D10" thru_hole circle
			(at 19.800062 4.100068 180)
			(size 0.906272 0.906272)
			(drill 0.499872)
			(layers "*.Cu" "*.Mask")
			(remove_unused_layers no)
			(net "GND")
			(clearance 0.0508)
			(thermal_gap 0.0508)
		)
		(pad "E1" thru_hole circle
			(at 0 5.199888 180)
			(size 0.906272 0.906272)
			(drill 0.499872)
			(layers "*.Cu" "*.Mask")
			(remove_unused_layers no)
			(net "GND")
			(clearance 0.0508)
			(thermal_gap 0.0508)
		)
		(pad "E3" thru_hole circle
			(at 4.400042 5.199888 180)
			(size 0.906272 0.906272)
			(drill 0.499872)
			(layers "*.Cu" "*.Mask")
			(remove_unused_layers no)
			(net "GND")
			(clearance 0.0508)
			(thermal_gap 0.0508)
		)
		(pad "E5" thru_hole circle
			(at 8.800084 5.199888 180)
			(size 0.906272 0.906272)
			(drill 0.499872)
			(layers "*.Cu" "*.Mask")
			(remove_unused_layers no)
			(net "GND")
			(clearance 0.0508)
			(thermal_gap 0.0508)
		)
		(pad "E7" thru_hole circle
			(at 13.199872 5.199888 180)
			(size 0.906272 0.906272)
			(drill 0.499872)
			(layers "*.Cu" "*.Mask")
			(remove_unused_layers no)
			(net "GND")
			(clearance 0.0508)
			(thermal_gap 0.0508)
		)
		(pad "E9" thru_hole circle
			(at 17.599914 5.199888 180)
			(size 0.906272 0.906272)
			(drill 0.499872)
			(layers "*.Cu" "*.Mask")
			(remove_unused_layers no)
			(net "GND")
			(clearance 0.0508)
			(thermal_gap 0.0508)
		)
		(pad "E10" thru_hole circle
			(at 19.800062 5.40004 180)
			(size 0.71628 0.71628)
			(drill 0.30988)
			(layers "*.Cu" "*.Mask")
			(remove_unused_layers no)
			(net "Net_8771")
			(clearance 0.0508)
			(thermal_gap 0.0508)
		)
		(pad "F9" thru_hole circle
			(at 17.599914 6.500114 180)
			(size 0.71628 0.71628)
			(drill 0.30988)
			(layers "*.Cu" "*.Mask")
			(remove_unused_layers no)
			(net "Net_8769")
			(clearance 0.0508)
			(thermal_gap 0.0508)
		)
		(pad "F10" thru_hole circle
			(at 19.800062 6.700012 180)
			(size 0.71628 0.71628)
			(drill 0.30988)
			(layers "*.Cu" "*.Mask")
			(remove_unused_layers no)
			(net "Net_8770")
			(clearance 0.0508)
			(thermal_gap 0.0508)
		)
		(pad "G2" thru_hole circle
			(at 2.199894 7.999984 180)
			(size 0.906272 0.906272)
			(drill 0.499872)
			(layers "*.Cu" "*.Mask")
			(remove_unused_layers no)
			(net "GND")
			(clearance 0.0508)
			(thermal_gap 0.0508)
		)
		(pad "G4" thru_hole circle
			(at 6.599936 7.999984 180)
			(size 0.906272 0.906272)
			(drill 0.499872)
			(layers "*.Cu" "*.Mask")
			(remove_unused_layers no)
			(net "GND")
			(clearance 0.0508)
			(thermal_gap 0.0508)
		)
		(pad "G6" thru_hole circle
			(at 10.999978 7.999984 180)
			(size 0.906272 0.906272)
			(drill 0.499872)
			(layers "*.Cu" "*.Mask")
			(remove_unused_layers no)
			(net "GND")
			(clearance 0.0508)
			(thermal_gap 0.0508)
		)
		(pad "G8" thru_hole circle
			(at 15.40002 7.999984 180)
			(size 0.906272 0.906272)
			(drill 0.499872)
			(layers "*.Cu" "*.Mask")
			(remove_unused_layers no)
			(net "GND")
			(clearance 0.0508)
			(thermal_gap 0.0508)
		)
		(pad "G9" thru_hole circle
			(at 17.599914 7.800086 180)
			(size 0.71628 0.71628)
			(drill 0.30988)
			(layers "*.Cu" "*.Mask")
			(remove_unused_layers no)
			(net "GPU_WP_HW_CTRL_R_N")
			(clearance 0.0508)
			(thermal_gap 0.0508)
		)
		(pad "G10" thru_hole circle
			(at 19.800062 7.999984 180)
			(size 0.906272 0.906272)
			(drill 0.499872)
			(layers "*.Cu" "*.Mask")
			(remove_unused_layers no)
			(net "GND")
			(clearance 0.0508)
			(thermal_gap 0.0508)
		)
		(pad "H1" thru_hole circle
			(at 0 9.100058 180)
			(size 0.906272 0.906272)
			(drill 0.499872)
			(layers "*.Cu" "*.Mask")
			(remove_unused_layers no)
			(net "GND")
			(clearance 0.0508)
			(thermal_gap 0.0508)
		)
		(pad "H3" thru_hole circle
			(at 4.400042 9.100058 180)
			(size 0.906272 0.906272)
			(drill 0.499872)
			(layers "*.Cu" "*.Mask")
			(remove_unused_layers no)
			(net "GND")
			(clearance 0.0508)
			(thermal_gap 0.0508)
		)
		(pad "H5" thru_hole circle
			(at 8.800084 9.100058 180)
			(size 0.906272 0.906272)
			(drill 0.499872)
			(layers "*.Cu" "*.Mask")
			(remove_unused_layers no)
			(net "GND")
			(clearance 0.0508)
			(thermal_gap 0.0508)
		)
		(pad "H7" thru_hole circle
			(at 13.199872 9.100058 180)
			(size 0.906272 0.906272)
			(drill 0.499872)
			(layers "*.Cu" "*.Mask")
			(remove_unused_layers no)
			(net "GND")
			(clearance 0.0508)
			(thermal_gap 0.0508)
		)
		(pad "H9" thru_hole circle
			(at 17.599914 9.100058 180)
			(size 0.906272 0.906272)
			(drill 0.499872)
			(layers "*.Cu" "*.Mask")
			(remove_unused_layers no)
			(net "GND")
			(clearance 0.0508)
			(thermal_gap 0.0508)
		)
		(pad "H10" thru_hole circle
			(at 19.800062 9.299956 180)
			(size 0.71628 0.71628)
			(drill 0.30988)
			(layers "*.Cu" "*.Mask")
			(remove_unused_layers no)
			(net "Net_8768")
			(clearance 0.0508)
			(thermal_gap 0.0508)
		)
		(pad "I9" thru_hole circle
			(at 17.599914 10.40003 180)
			(size 0.71628 0.71628)
			(drill 0.30988)
			(layers "*.Cu" "*.Mask")
			(remove_unused_layers no)
			(net "Net_8767")
			(clearance 0.0508)
			(thermal_gap 0.0508)
		)
		(pad "I10" thru_hole circle
			(at 19.800062 10.599928 180)
			(size 0.71628 0.71628)
			(drill 0.30988)
			(layers "*.Cu" "*.Mask")
			(remove_unused_layers no)
			(net "GPU_3V3IO_RSVD4")
			(clearance 0.0508)
			(thermal_gap 0.0508)
		)
		(pad "J2" thru_hole circle
			(at 2.199894 11.8999 180)
			(size 0.906272 0.906272)
			(drill 0.499872)
			(layers "*.Cu" "*.Mask")
			(remove_unused_layers no)
			(net "GND")
			(clearance 0.0508)
			(thermal_gap 0.0508)
		)
		(pad "J4" thru_hole circle
			(at 6.599936 11.8999 180)
			(size 0.906272 0.906272)
			(drill 0.499872)
			(layers "*.Cu" "*.Mask")
			(remove_unused_layers no)
			(net "GND")
			(clearance 0.0508)
			(thermal_gap 0.0508)
		)
		(pad "J6" thru_hole circle
			(at 10.999978 11.8999 180)
			(size 0.906272 0.906272)
			(drill 0.499872)
			(layers "*.Cu" "*.Mask")
			(remove_unused_layers no)
			(net "GND")
			(clearance 0.0508)
			(thermal_gap 0.0508)
		)
		(pad "J8" thru_hole circle
			(at 15.40002 11.8999 180)
			(size 0.906272 0.906272)
			(drill 0.499872)
			(layers "*.Cu" "*.Mask")
			(remove_unused_layers no)
			(net "GND")
			(clearance 0.0508)
			(thermal_gap 0.0508)
		)
		(pad "J9" thru_hole circle
			(at 17.599914 11.700002 180)
			(size 0.71628 0.71628)
			(drill 0.30988)
			(layers "*.Cu" "*.Mask")
			(remove_unused_layers no)
			(net "Net_8766")
			(clearance 0.0508)
			(thermal_gap 0.0508)
		)
		(pad "J10" thru_hole circle
			(at 19.800062 11.8999 180)
			(size 0.906272 0.906272)
			(drill 0.499872)
			(layers "*.Cu" "*.Mask")
			(remove_unused_layers no)
			(net "GND")
			(clearance 0.0508)
			(thermal_gap 0.0508)
		)
		(pad "K1" thru_hole circle
			(at 0 12.999974 180)
			(size 0.906272 0.906272)
			(drill 0.499872)
			(layers "*.Cu" "*.Mask")
			(remove_unused_layers no)
			(net "GND")
			(clearance 0.0508)
			(thermal_gap 0.0508)
		)
		(pad "K3" thru_hole circle
			(at 4.400042 12.999974 180)
			(size 0.906272 0.906272)
			(drill 0.499872)
			(layers "*.Cu" "*.Mask")
			(remove_unused_layers no)
			(net "GND")
			(clearance 0.0508)
			(thermal_gap 0.0508)
		)
		(pad "K5" thru_hole circle
			(at 8.800084 12.999974 180)
			(size 0.906272 0.906272)
			(drill 0.499872)
			(layers "*.Cu" "*.Mask")
			(remove_unused_layers no)
			(net "GND")
			(clearance 0.0508)
			(thermal_gap 0.0508)
		)
		(pad "K7" thru_hole circle
			(at 13.199872 12.999974 180)
			(size 0.906272 0.906272)
			(drill 0.499872)
			(layers "*.Cu" "*.Mask")
			(remove_unused_layers no)
			(net "GND")
			(clearance 0.0508)
			(thermal_gap 0.0508)
		)
		(pad "K9" thru_hole circle
			(at 17.599914 12.999974 180)
			(size 0.906272 0.906272)
			(drill 0.499872)
			(layers "*.Cu" "*.Mask")
			(remove_unused_layers no)
			(net "GND")
			(clearance 0.0508)
			(thermal_gap 0.0508)
		)
		(pad "K10" thru_hole circle
			(at 19.800062 13.199872 180)
			(size 0.71628 0.71628)
			(drill 0.30988)
			(layers "*.Cu" "*.Mask")
			(remove_unused_layers no)
			(net "Net_8765")
			(clearance 0.0508)
			(thermal_gap 0.0508)
		)
		(pad "L9" thru_hole circle
			(at 17.599914 14.299946 180)
			(size 0.71628 0.71628)
			(drill 0.30988)
			(layers "*.Cu" "*.Mask")
			(remove_unused_layers no)
			(net "Net_8763")
			(clearance 0.0508)
			(thermal_gap 0.0508)
		)
		(pad "L10" thru_hole circle
			(at 19.800062 14.500098 180)
			(size 0.71628 0.71628)
			(drill 0.30988)
			(layers "*.Cu" "*.Mask")
			(remove_unused_layers no)
			(net "Net_8764")
			(clearance 0.0508)
			(thermal_gap 0.0508)
		)
		(pad "M1_2" thru_hole circle
			(at 2.199894 15.80007 180)
			(size 0.906272 0.906272)
			(drill 0.499872)
			(layers "*.Cu" "*.Mask")
			(remove_unused_layers no)
			(net "GND")
			(clearance 0.0508)
			(thermal_gap 0.0508)
		)
		(pad "M1_4" thru_hole circle
			(at 6.599936 15.80007 180)
			(size 0.906272 0.906272)
			(drill 0.499872)
			(layers "*.Cu" "*.Mask")
			(remove_unused_layers no)
			(net "GND")
			(clearance 0.0508)
			(thermal_gap 0.0508)
		)
		(pad "M1_6" thru_hole circle
			(at 10.999978 15.80007 180)
			(size 0.906272 0.906272)
			(drill 0.499872)
			(layers "*.Cu" "*.Mask")
			(remove_unused_layers no)
			(net "GND")
			(clearance 0.0508)
			(thermal_gap 0.0508)
		)
		(pad "M1_8" thru_hole circle
			(at 15.40002 15.80007 180)
			(size 0.906272 0.906272)
			(drill 0.499872)
			(layers "*.Cu" "*.Mask")
			(remove_unused_layers no)
			(net "GND")
			(clearance 0.0508)
			(thermal_gap 0.0508)
		)
		(pad "M1_10" thru_hole circle
			(at 19.800062 15.80007 180)
			(size 0.906272 0.906272)
			(drill 0.499872)
			(layers "*.Cu" "*.Mask")
			(remove_unused_layers no)
			(net "GND")
			(clearance 0.0508)
			(thermal_gap 0.0508)
		)
		(pad "M2_2" thru_hole circle
			(at 2.199894 26.2001 180)
			(size 0.906272 0.906272)
			(drill 0.499872)
			(layers "*.Cu" "*.Mask")
			(remove_unused_layers no)
			(net "GND")
			(clearance 0.0508)
			(thermal_gap 0.0508)
		)
		(pad "M2_4" thru_hole circle
			(at 6.599936 26.2001 180)
			(size 0.906272 0.906272)
			(drill 0.499872)
			(layers "*.Cu" "*.Mask")
			(remove_unused_layers no)
			(net "GND")
			(clearance 0.0508)
			(thermal_gap 0.0508)
		)
		(pad "M2_6" thru_hole circle
			(at 10.999978 26.2001 180)
			(size 0.906272 0.906272)
			(drill 0.499872)
			(layers "*.Cu" "*.Mask")
			(remove_unused_layers no)
			(net "GND")
			(clearance 0.0508)
			(thermal_gap 0.0508)
		)
		(pad "M2_8" thru_hole circle
			(at 15.40002 26.2001 180)
			(size 0.906272 0.906272)
			(drill 0.499872)
			(layers "*.Cu" "*.Mask")
			(remove_unused_layers no)
			(net "GND")
			(clearance 0.0508)
			(thermal_gap 0.0508)
		)
		(pad "M2_10" thru_hole circle
			(at 19.800062 26.2001 180)
			(size 0.906272 0.906272)
			(drill 0.499872)
			(layers "*.Cu" "*.Mask")
			(remove_unused_layers no)
			(net "GND")
			(clearance 0.0508)
			(thermal_gap 0.0508)
		)
		(pad "M9" thru_hole circle
			(at 17.599914 15.599918 180)
			(size 0.71628 0.71628)
			(drill 0.30988)
			(layers "*.Cu" "*.Mask")
			(remove_unused_layers no)
			(net "Net_8762")
			(clearance 0.0508)
			(thermal_gap 0.0508)
		)
		(pad "N1_1" thru_hole circle
			(at 0 16.89989 180)
			(size 0.906272 0.906272)
			(drill 0.499872)
			(layers "*.Cu" "*.Mask")
			(remove_unused_layers no)
			(net "GND")
			(clearance 0.0508)
			(thermal_gap 0.0508)
		)
		(pad "N1_3" thru_hole circle
			(at 4.400042 16.89989 180)
			(size 0.906272 0.906272)
			(drill 0.499872)
			(layers "*.Cu" "*.Mask")
			(remove_unused_layers no)
			(net "GND")
			(clearance 0.0508)
			(thermal_gap 0.0508)
		)
		(pad "N1_5" thru_hole circle
			(at 8.800084 16.89989 180)
			(size 0.906272 0.906272)
			(drill 0.499872)
			(layers "*.Cu" "*.Mask")
			(remove_unused_layers no)
			(net "GND")
			(clearance 0.0508)
			(thermal_gap 0.0508)
		)
		(pad "N1_7" thru_hole circle
			(at 13.199872 16.89989 180)
			(size 0.906272 0.906272)
			(drill 0.499872)
			(layers "*.Cu" "*.Mask")
			(remove_unused_layers no)
			(net "GND")
			(clearance 0.0508)
			(thermal_gap 0.0508)
		)
		(pad "N1_9" thru_hole circle
			(at 17.599914 16.89989 180)
			(size 0.906272 0.906272)
			(drill 0.499872)
			(layers "*.Cu" "*.Mask")
			(remove_unused_layers no)
			(net "GND")
			(clearance 0.0508)
			(thermal_gap 0.0508)
		)
		(pad "N2_1" thru_hole circle
			(at 0 27.29992 180)
			(size 0.906272 0.906272)
			(drill 0.499872)
			(layers "*.Cu" "*.Mask")
			(remove_unused_layers no)
			(net "GND")
			(clearance 0.0508)
			(thermal_gap 0.0508)
		)
	)
)
